# T6G (Grand Teton) — schematic netlist excerpt (pin names and nets, part order shuffled) for the footprints in the layout excerpt that follows; sources: Cadence DE-HDL packaged netlist, KiCad conversion of 04192023_DAF0TMB3IC0_F0TG_MB_C_brd_V02_OCP.brd

C2052  Q_CAP  0.1UF 25V 10% X7R  pkg 0402  page 257 : A = P3V3_ADC128_VCC ; B = GND
PC61  Q_CAP  22UF 16V 20% X6S  pkg C0805  page 226 : A = SW_P12V_AUX_PVDD18_S5_P1_FLT ; B = GND
D82  Q_LED  IC  pkg SMLF  page 256 : A = LED_PWRGD_PVDDCR_CPU1_P1_R ; C = LED_PWRGD_PVDDCR_CPU1_P1_D

(kicad_pcb
	(version 20260206)
	(generator "pcbnew")
	(generator_version "10.0")
	(general
		(thickness 1.6)
		(legacy_teardrops no)
	)
	(paper "A4")
	(title_block
		(title "04192023_DAF0TMB3IC0_F0TG_MB_C_brd_V02_OCP.brd")
		(comment 1 "Grand Teton / footprints 2428-2430 of 8354")
	)
	(layers
		(0 "F.Cu" signal "TOP")
		(4 "In1.Cu" signal "GND")
		(6 "In2.Cu" signal "IN1")
		(8 "In3.Cu" signal "GND1")
		(10 "In4.Cu" signal "IN2")
		(12 "In5.Cu" signal "GND2")
		(14 "In6.Cu" signal "IN3")
		(16 "In7.Cu" signal "GND3")
		(18 "In8.Cu" signal "VCC")
		(20 "In9.Cu" signal "VCC1")
		(22 "In10.Cu" signal "GND4")
		(24 "In11.Cu" signal "IN4")
		(26 "In12.Cu" signal "GND5")
		(28 "In13.Cu" signal "IN5")
		(30 "In14.Cu" signal "GND6")
		(32 "In15.Cu" signal "IN6")
		(34 "In16.Cu" signal "GND7")
		(2 "B.Cu" signal "BOTTOM")
		(9 "F.Adhes" user "F.Adhesive")
		(11 "B.Adhes" user "B.Adhesive")
		(13 "F.Paste" user "Package Geometry/Pastemask Top")
		(15 "B.Paste" user "Package Geometry/Pastemask Bottom")
		(5 "F.SilkS" user "Ref Des/Silkscreen Top")
		(7 "B.SilkS" user "Ref Des/Silkscreen Bottom")
		(1 "F.Mask" user "Board Geometry/Soldermask Top")
		(3 "B.Mask" user "Board Geometry/Soldermask Bottom")
		(17 "Dwgs.User" user "User.Drawings")
		(19 "Cmts.User" user "User.Comments")
		(21 "Eco1.User" user "User.Eco1")
		(23 "Eco2.User" user "User.Eco2")
		(25 "Edge.Cuts" user "Board Geometry/Outline")
		(27 "Margin" user)
		(31 "F.CrtYd" user "Package Geometry/Place Bound Top")
		(29 "B.CrtYd" user "Package Geometry/Place Bound Bottom")
		(35 "F.Fab" user "Ref Des/Assembly Top")
		(33 "B.Fab" user "Ref Des/Assembly Bottom")
	)
	(footprint ""
		(layer "F.Cu")
		(at 303.200308 -43.989498 180)
		(property "Reference" "C2052"
			(at 0 0 180)
			(layer "F.SilkS")
			(hide yes)
			(effects
				(font
					(size 1.27 1.27)
				)
			)
		)
		(property "Value" ""
			(at 0 0 180)
			(layer "F.Fab")
			(effects
				(font
					(size 1.27 1.27)
				)
			)
		)
		(duplicate_pad_numbers_are_jumpers no)
		(fp_line
			(start 0.7874 0.4064)
			(end -0.7874 0.4064)
			(stroke
				(width 0.1524)
				(type default)
			)
			(layer "F.SilkS")
		)
		(fp_line
			(start 0.7874 -0.4064)
			(end 0.7874 0.4064)
			(stroke
				(width 0.1524)
				(type default)
			)
			(layer "F.SilkS")
		)
		(fp_line
			(start -0.7874 0.4064)
			(end -0.7874 -0.4064)
			(stroke
				(width 0.1524)
				(type default)
			)
			(layer "F.SilkS")
		)
		(fp_line
			(start -0.7874 -0.4064)
			(end 0.7874 -0.4064)
			(stroke
				(width 0.1524)
				(type default)
			)
			(layer "F.SilkS")
		)
		(fp_line
			(start 0.67945 0.3048)
			(end 0.120396 0.3048)
			(stroke
				(width 0.1)
				(type default)
			)
			(layer "F.Fab")
		)
		(fp_line
			(start 0.67945 -0.3048)
			(end 0.67945 0.3048)
			(stroke
				(width 0.1)
				(type default)
			)
			(layer "F.Fab")
		)
		(fp_line
			(start 0.12065 -0.2794)
			(end 0.12065 -0.3048)
			(stroke
				(width 0.1)
				(type default)
			)
			(layer "F.Fab")
		)
		(fp_line
			(start 0.12065 -0.3048)
			(end 0.67945 -0.3048)
			(stroke
				(width 0.1)
				(type default)
			)
			(layer "F.Fab")
		)
		(fp_line
			(start 0.120396 0.3048)
			(end 0.120396 0.2794)
			(stroke
				(width 0.1)
				(type default)
			)
			(layer "F.Fab")
		)
		(fp_line
			(start 0.120396 0.2794)
			(end -0.12065 0.2794)
			(stroke
				(width 0.1)
				(type default)
			)
			(layer "F.Fab")
		)
		(fp_line
			(start -0.12065 0.3048)
			(end -0.67945 0.3048)
			(stroke
				(width 0.1)
				(type default)
			)
			(layer "F.Fab")
		)
		(fp_line
			(start -0.12065 0.2794)
			(end -0.12065 0.3048)
			(stroke
				(width 0.1)
				(type default)
			)
			(layer "F.Fab")
		)
		(fp_line
			(start -0.12065 -0.2794)
			(end 0.12065 -0.2794)
			(stroke
				(width 0.1)
				(type default)
			)
			(layer "F.Fab")
		)
		(fp_line
			(start -0.12065 -0.305054)
			(end -0.12065 -0.2794)
			(stroke
				(width 0.1)
				(type default)
			)
			(layer "F.Fab")
		)
		(fp_line
			(start -0.67945 0.3048)
			(end -0.67945 -0.305054)
			(stroke
				(width 0.1)
				(type default)
			)
			(layer "F.Fab")
		)
		(fp_line
			(start -0.67945 -0.305054)
			(end -0.12065 -0.305054)
			(stroke
				(width 0.1)
				(type default)
			)
			(layer "F.Fab")
		)
		(pad "1" smd circle
			(at -0.40005 0 180)
			(size 0 0)
			(layers "F.Cu" "F.Mask" "F.Paste")
			(net "P3V3_ADC128_VCC")
		)
		(pad "2" smd circle
			(at 0.40005 0 180)
			(size 0 0)
			(layers "F.Cu" "F.Mask" "F.Paste")
			(net "GND")
		)
	)
	(footprint ""
		(layer "F.Cu")
		(at 340.891876 -70.098412 90)
		(property "Reference" "D82"
			(at -3.934714 -0.691642 90)
			(unlocked yes)
			(layer "F.SilkS")
			(effects
				(font
					(size 0.7874 0.5842)
					(thickness 0.1524)
				)
				(justify left)
			)
		)
		(property "Value" ""
			(at 0 0 90)
			(layer "F.Fab")
			(effects
				(font
					(size 1.27 1.27)
				)
			)
		)
		(duplicate_pad_numbers_are_jumpers no)
		(fp_line
			(start 1.16078 -0.4826)
			(end 1.16078 0.4826)
			(stroke
				(width 0.1524)
				(type default)
			)
			(layer "F.SilkS")
		)
		(fp_line
			(start 1.03378 -0.4826)
			(end 1.03378 0.4826)
			(stroke
				(width 0.1524)
				(type default)
			)
			(layer "F.SilkS")
		)
		(fp_line
			(start 0.90678 -0.4826)
			(end 0.90678 0.4826)
			(stroke
				(width 0.1524)
				(type default)
			)
			(layer "F.SilkS")
		)
		(fp_line
			(start -0.64008 -0.4826)
			(end 1.16078 -0.4826)
			(stroke
				(width 0.1524)
				(type default)
			)
			(layer "F.SilkS")
		)
		(fp_line
			(start -0.79248 -0.4826)
			(end 1.03378 -0.4826)
			(stroke
				(width 0.1524)
				(type default)
			)
			(layer "F.SilkS")
		)
		(fp_line
			(start -0.89408 -0.4826)
			(end 0.90678 -0.4826)
			(stroke
				(width 0.1524)
				(type default)
			)
			(layer "F.SilkS")
		)
		(fp_line
			(start 1.16078 0.4826)
			(end -0.64008 0.4826)
			(stroke
				(width 0.1524)
				(type default)
			)
			(layer "F.SilkS")
		)
		(fp_line
			(start 1.03378 0.4826)
			(end -0.79248 0.4826)
			(stroke
				(width 0.1524)
				(type default)
			)
			(layer "F.SilkS")
		)
		(fp_line
			(start 0.90678 0.4826)
			(end -0.90678 0.4826)
			(stroke
				(width 0.1524)
				(type default)
			)
			(layer "F.SilkS")
		)
		(fp_line
			(start -0.90678 0.4826)
			(end -0.90678 -0.4699)
			(stroke
				(width 0.1524)
				(type default)
			)
			(layer "F.SilkS")
		)
		(fp_line
			(start 0.499872 -0.249936)
			(end 0.499872 0.249936)
			(stroke
				(width 0.1)
				(type default)
			)
			(layer "F.Fab")
		)
		(fp_line
			(start -0.499872 -0.249936)
			(end 0.499872 -0.249936)
			(stroke
				(width 0.1)
				(type default)
			)
			(layer "F.Fab")
		)
		(fp_line
			(start 0.499872 0.249936)
			(end -0.499872 0.249936)
			(stroke
				(width 0.1)
				(type default)
			)
			(layer "F.Fab")
		)
		(fp_line
			(start -0.499872 0.249936)
			(end -0.499872 -0.249936)
			(stroke
				(width 0.1)
				(type default)
			)
			(layer "F.Fab")
		)
		(pad "A" smd rect
			(at -0.47498 0 90)
			(size 0.6096 0.7112)
			(layers "F.Cu" "F.Mask" "F.Paste")
			(net "LED_PWRGD_PVDDCR_CPU1_P1_R")
		)
		(pad "C" smd rect
			(at 0.47498 0 90)
			(size 0.6096 0.7112)
			(layers "F.Cu" "F.Mask" "F.Paste")
			(net "LED_PWRGD_PVDDCR_CPU1_P1_D")
		)
	)
	(footprint ""
		(layer "F.Cu")
		(at 73.466706 -152.990804 90)
		(property "Reference" "PC61"
			(at 0 0 90)
			(layer "F.SilkS")
			(hide yes)
			(effects
				(font
					(size 1.27 1.27)
				)
			)
		)
		(property "Value" ""
			(at 0 0 90)
			(layer "F.Fab")
			(effects
				(font
					(size 1.27 1.27)
				)
			)
		)
		(duplicate_pad_numbers_are_jumpers no)
		(fp_line
			(start 1.524 -0.762)
			(end 1.524 0.762)
			(stroke
				(width 0.1524)
				(type default)
			)
			(layer "F.SilkS")
		)
		(fp_line
			(start -1.524 -0.762)
			(end 1.524 -0.762)
			(stroke
				(width 0.1524)
				(type default)
			)
			(layer "F.SilkS")
		)
		(fp_line
			(start 1.524 0.762)
			(end -1.524 0.762)
			(stroke
				(width 0.1524)
				(type default)
			)
			(layer "F.SilkS")
		)
		(fp_line
			(start -1.524 0.762)
			(end -1.524 -0.762)
			(stroke
				(width 0.1524)
				(type default)
			)
			(layer "F.SilkS")
		)
		(fp_line
			(start 1.1049 -0.724916)
			(end -1.1049 -0.724916)
			(stroke
				(width 0.1)
				(type default)
			)
			(layer "F.Fab")
		)
		(fp_line
			(start -1.1049 -0.724916)
			(end -1.1049 0.724916)
			(stroke
				(width 0.1)
				(type default)
			)
			(layer "F.Fab")
		)
		(fp_line
			(start 1.1049 0.724916)
			(end 1.1049 -0.724916)
			(stroke
				(width 0.1)
				(type default)
			)
			(layer "F.Fab")
		)
		(fp_line
			(start -1.1049 0.724916)
			(end 1.1049 0.724916)
			(stroke
				(width 0.1)
				(type default)
			)
			(layer "F.Fab")
		)
		(pad "1" smd rect
			(at -0.889 0 270)
			(size 1.016 1.27)
			(layers "F.Cu" "F.Mask" "F.Paste")
			(net "SW_P12V_AUX_PVDD18_S5_P1_FLT")
		)
		(pad "2" smd rect
			(at 0.889 0 270)
			(size 1.016 1.27)
			(layers "F.Cu" "F.Mask" "F.Paste")
			(net "GND")
		)
	)
)
